# T6G (Grand Teton) — schematic netlist excerpt (pin names and nets, part order shuffled) for the footprints in the layout excerpt that follows; sources: Cadence DE-HDL packaged netlist, KiCad conversion of 04192023_DAF0TMB3IC0_F0TG_MB_C_brd_V02_OCP.brd

PR218  Q_RES  1K 1% EMPTY  pkg 0402LF  page 217 : A = PVDD18_S5_P1 ; B = SVID_PVDDCR_CPU1_P1_SVTI
C1132  Q_CAP  0.1UF 16V 10% X7R  pkg C0402  page 83 : A = P1V8_AUX ; B = GND

(kicad_pcb
	(version 20260206)
	(generator "pcbnew")
	(generator_version "10.0")
	(general
		(thickness 1.6)
		(legacy_teardrops no)
	)
	(paper "A4")
	(title_block
		(title "04192023_DAF0TMB3IC0_F0TG_MB_C_brd_V02_OCP.brd")
		(comment 1 "Grand Teton / footprints 8174-8175 of 8354")
	)
	(layers
		(0 "F.Cu" signal "TOP")
		(4 "In1.Cu" signal "GND")
		(6 "In2.Cu" signal "IN1")
		(8 "In3.Cu" signal "GND1")
		(10 "In4.Cu" signal "IN2")
		(12 "In5.Cu" signal "GND2")
		(14 "In6.Cu" signal "IN3")
		(16 "In7.Cu" signal "GND3")
		(18 "In8.Cu" signal "VCC")
		(20 "In9.Cu" signal "VCC1")
		(22 "In10.Cu" signal "GND4")
		(24 "In11.Cu" signal "IN4")
		(26 "In12.Cu" signal "GND5")
		(28 "In13.Cu" signal "IN5")
		(30 "In14.Cu" signal "GND6")
		(32 "In15.Cu" signal "IN6")
		(34 "In16.Cu" signal "GND7")
		(2 "B.Cu" signal "BOTTOM")
		(9 "F.Adhes" user "F.Adhesive")
		(11 "B.Adhes" user "B.Adhesive")
		(13 "F.Paste" user "Package Geometry/Pastemask Top")
		(15 "B.Paste" user "Package Geometry/Pastemask Bottom")
		(5 "F.SilkS" user "Ref Des/Silkscreen Top")
		(7 "B.SilkS" user "Ref Des/Silkscreen Bottom")
		(1 "F.Mask" user "Board Geometry/Soldermask Top")
		(3 "B.Mask" user "Board Geometry/Soldermask Bottom")
		(17 "Dwgs.User" user "User.Drawings")
		(19 "Cmts.User" user "User.Comments")
		(21 "Eco1.User" user "User.Eco1")
		(23 "Eco2.User" user "User.Eco2")
		(25 "Edge.Cuts" user "Board Geometry/Outline")
		(27 "Margin" user)
		(31 "F.CrtYd" user "Package Geometry/Place Bound Top")
		(29 "B.CrtYd" user "Package Geometry/Place Bound Bottom")
		(35 "F.Fab" user "Ref Des/Assembly Top")
		(33 "B.Fab" user "Ref Des/Assembly Bottom")
	)
	(footprint ""
		(layer "B.Cu")
		(at 22.479 -357.632 180)
		(property "Reference" "PR218"
			(at 0 0 0)
			(layer "B.SilkS")
			(hide yes)
			(effects
				(font
					(size 1.27 1.27)
				)
				(justify mirror)
			)
		)
		(property "Value" ""
			(at 0 0 0)
			(layer "B.Fab")
			(effects
				(font
					(size 1.27 1.27)
				)
				(justify mirror)
			)
		)
		(duplicate_pad_numbers_are_jumpers no)
		(fp_line
			(start 0.7874 0.4064)
			(end 0.7874 -0.4064)
			(stroke
				(width 0.1524)
				(type default)
			)
			(layer "B.SilkS")
		)
		(fp_line
			(start 0.7874 -0.4064)
			(end -0.7874 -0.4064)
			(stroke
				(width 0.1524)
				(type default)
			)
			(layer "B.SilkS")
		)
		(fp_line
			(start -0.7874 0.4064)
			(end 0.7874 0.4064)
			(stroke
				(width 0.1524)
				(type default)
			)
			(layer "B.SilkS")
		)
		(fp_line
			(start -0.7874 -0.4064)
			(end -0.7874 0.4064)
			(stroke
				(width 0.1524)
				(type default)
			)
			(layer "B.SilkS")
		)
		(fp_line
			(start 0.67945 0.3048)
			(end 0.67945 -0.305054)
			(stroke
				(width 0.1)
				(type default)
			)
			(layer "B.Fab")
		)
		(fp_line
			(start 0.67945 -0.305054)
			(end 0.12065 -0.305054)
			(stroke
				(width 0.1)
				(type default)
			)
			(layer "B.Fab")
		)
		(fp_line
			(start 0.12065 0.3048)
			(end 0.67945 0.3048)
			(stroke
				(width 0.1)
				(type default)
			)
			(layer "B.Fab")
		)
		(fp_line
			(start 0.12065 0.2794)
			(end 0.12065 0.3048)
			(stroke
				(width 0.1)
				(type default)
			)
			(layer "B.Fab")
		)
		(fp_line
			(start 0.12065 -0.2794)
			(end -0.12065 -0.2794)
			(stroke
				(width 0.1)
				(type default)
			)
			(layer "B.Fab")
		)
		(fp_line
			(start 0.12065 -0.305054)
			(end 0.12065 -0.2794)
			(stroke
				(width 0.1)
				(type default)
			)
			(layer "B.Fab")
		)
		(fp_line
			(start -0.120396 0.3048)
			(end -0.120396 0.2794)
			(stroke
				(width 0.1)
				(type default)
			)
			(layer "B.Fab")
		)
		(fp_line
			(start -0.120396 0.2794)
			(end 0.12065 0.2794)
			(stroke
				(width 0.1)
				(type default)
			)
			(layer "B.Fab")
		)
		(fp_line
			(start -0.12065 -0.2794)
			(end -0.12065 -0.3048)
			(stroke
				(width 0.1)
				(type default)
			)
			(layer "B.Fab")
		)
		(fp_line
			(start -0.12065 -0.3048)
			(end -0.67945 -0.3048)
			(stroke
				(width 0.1)
				(type default)
			)
			(layer "B.Fab")
		)
		(fp_line
			(start -0.67945 0.3048)
			(end -0.120396 0.3048)
			(stroke
				(width 0.1)
				(type default)
			)
			(layer "B.Fab")
		)
		(fp_line
			(start -0.67945 -0.3048)
			(end -0.67945 0.3048)
			(stroke
				(width 0.1)
				(type default)
			)
			(layer "B.Fab")
		)
		(pad "1" smd circle
			(at 0.40005 0)
			(size 0 0)
			(layers "B.Cu" "B.Mask" "B.Paste")
			(net "PVDD18_S5_P1")
		)
		(pad "2" smd circle
			(at -0.40005 0)
			(size 0 0)
			(layers "B.Cu" "B.Mask" "B.Paste")
			(net "SVID_PVDDCR_CPU1_P1_SVTI")
		)
	)
	(footprint ""
		(layer "B.Cu")
		(at 184.332372 -118.242842 90)
		(property "Reference" "C1132"
			(at 0 0 90)
			(layer "B.SilkS")
			(hide yes)
			(effects
				(font
					(size 1.27 1.27)
				)
				(justify mirror)
			)
		)
		(property "Value" ""
			(at 0 0 90)
			(layer "B.Fab")
			(effects
				(font
					(size 1.27 1.27)
				)
				(justify mirror)
			)
		)
		(duplicate_pad_numbers_are_jumpers no)
		(fp_line
			(start 0.69215 -0.2921)
			(end -0.69215 -0.2921)
			(stroke
				(width 0.1524)
				(type default)
			)
			(layer "B.SilkS")
		)
		(fp_line
			(start -0.69215 -0.2921)
			(end -0.69215 0.2921)
			(stroke
				(width 0.1524)
				(type default)
			)
			(layer "B.SilkS")
		)
		(fp_line
			(start 0.69215 0.2921)
			(end 0.69215 -0.2921)
			(stroke
				(width 0.1524)
				(type default)
			)
			(layer "B.SilkS")
		)
		(fp_line
			(start -0.69215 0.2921)
			(end 0.69215 0.2921)
			(stroke
				(width 0.1524)
				(type default)
			)
			(layer "B.SilkS")
		)
		(fp_line
			(start 0.51435 -0.2794)
			(end -0.51435 -0.2794)
			(stroke
				(width 0.1)
				(type default)
			)
			(layer "B.Fab")
		)
		(fp_line
			(start -0.51435 -0.2794)
			(end -0.51435 0.2794)
			(stroke
				(width 0.1)
				(type default)
			)
			(layer "B.Fab")
		)
		(fp_line
			(start 0.51435 0.2794)
			(end 0.51435 -0.2794)
			(stroke
				(width 0.1)
				(type default)
			)
			(layer "B.Fab")
		)
		(fp_line
			(start -0.51435 0.2794)
			(end 0.51435 0.2794)
			(stroke
				(width 0.1)
				(type default)
			)
			(layer "B.Fab")
		)
		(pad "1" smd circle
			(at 0.40005 0 270)
			(size 0 0)
			(layers "B.Cu" "B.Mask" "B.Paste")
			(net "P1V8_AUX")
		)
		(pad "2" smd circle
			(at -0.40005 0 270)
			(size 0 0)
			(layers "B.Cu" "B.Mask" "B.Paste")
			(net "GND")
		)
		(zone
			(layer "B.Cu")
			(hatch none 0.5)
			(connect_pads
				(clearance 0)
			)
			(min_thickness 0.25)
			(keepout
				(tracks not_allowed)
				(vias allowed)
				(pads allowed)
				(copperpour not_allowed)
				(footprints allowed)
			)
			(placement
				(enabled no)
				(sheetname "")
			)
			(fill
				(thermal_gap 0.5)
				(thermal_bridge_width 0.5)
				(island_removal_mode 0)
			)
			(polygon
				(pts
					(xy 184.186322 -118.142512) (xy 184.186322 -118.341902) (xy 184.244488 -118.433342) (xy 184.420002 -118.433342)
					(xy 184.478168 -118.341902) (xy 184.478168 -118.142512) (xy 184.420002 -118.052342) (xy 184.244742 -118.052342)
				)
			)
		)
	)
)
